# S9S_MB_2U (Grand Teton) — schematic netlist excerpt (pin names and nets, part order shuffled) for the footprints in the layout excerpt that follows; sources: Cadence DE-HDL packaged netlist, KiCad conversion of 03242023_DA0F0TMBIJ0_F0T_Motherboard_J_brd_V01_OCP.brd

R3172  Q_RES  0 5% CHIP  pkg 0402LF  page 159 : A = OCP_V3_2_AUX_PWR_EN ; B = OCP_V3_2_AUX_PWR_EN_R
C537  Q_CAP  0.1UF 25V 10% X7R  pkg 0402  page 230 : A = P3V3_AUX ; B = GND

(kicad_pcb
	(version 20260206)
	(generator "pcbnew")
	(generator_version "10.0")
	(general
		(thickness 1.6)
		(legacy_teardrops no)
	)
	(paper "A4")
	(title_block
		(title "03242023_DA0F0TMBIJ0_F0T_Motherboard_J_brd_V01_OCP.brd")
		(comment 1 "Grand Teton / footprints 3733-3734 of 6105")
	)
	(layers
		(0 "F.Cu" signal "TOP")
		(4 "In1.Cu" signal "GND")
		(6 "In2.Cu" signal "IN1")
		(8 "In3.Cu" signal "GND1")
		(10 "In4.Cu" signal "IN2")
		(12 "In5.Cu" signal "GND2")
		(14 "In6.Cu" signal "IN3")
		(16 "In7.Cu" signal "GND3")
		(18 "In8.Cu" signal "VCC")
		(20 "In9.Cu" signal "VCC1")
		(22 "In10.Cu" signal "GND4")
		(24 "In11.Cu" signal "IN4")
		(26 "In12.Cu" signal "GND5")
		(28 "In13.Cu" signal "IN5")
		(30 "In14.Cu" signal "GND6")
		(32 "In15.Cu" signal "IN6")
		(34 "In16.Cu" signal "GND7")
		(2 "B.Cu" signal "BOTTOM")
		(9 "F.Adhes" user "F.Adhesive")
		(11 "B.Adhes" user "B.Adhesive")
		(13 "F.Paste" user "Package Geometry/Pastemask Top")
		(15 "B.Paste" user "Package Geometry/Pastemask Bottom")
		(5 "F.SilkS" user "Ref Des/Silkscreen Top")
		(7 "B.SilkS" user "Ref Des/Silkscreen Bottom")
		(1 "F.Mask" user "Board Geometry/Soldermask Top")
		(3 "B.Mask" user "Board Geometry/Soldermask Bottom")
		(17 "Dwgs.User" user "User.Drawings")
		(19 "Cmts.User" user "User.Comments")
		(21 "Eco1.User" user "User.Eco1")
		(23 "Eco2.User" user "User.Eco2")
		(25 "Edge.Cuts" user "Board Geometry/Outline")
		(27 "Margin" user)
		(31 "F.CrtYd" user "Package Geometry/Place Bound Top")
		(29 "B.CrtYd" user "Package Geometry/Place Bound Bottom")
		(35 "F.Fab" user "Ref Des/Assembly Top")
		(33 "B.Fab" user "Ref Des/Assembly Bottom")
	)
	(footprint ""
		(layer "F.Cu")
		(at 60.25388 -16.220948 -90)
		(property "Reference" "R3172"
			(at 0 0 270)
			(layer "F.SilkS")
			(hide yes)
			(effects
				(font
					(size 1.27 1.27)
				)
			)
		)
		(property "Value" ""
			(at 0 0 270)
			(layer "F.Fab")
			(effects
				(font
					(size 1.27 1.27)
				)
			)
		)
		(duplicate_pad_numbers_are_jumpers no)
		(fp_line
			(start -0.7874 0.4064)
			(end -0.7874 -0.4064)
			(stroke
				(width 0.1524)
				(type default)
			)
			(layer "F.SilkS")
		)
		(fp_line
			(start 0.7874 0.4064)
			(end -0.7874 0.4064)
			(stroke
				(width 0.1524)
				(type default)
			)
			(layer "F.SilkS")
		)
		(fp_line
			(start -0.7874 -0.4064)
			(end 0.7874 -0.4064)
			(stroke
				(width 0.1524)
				(type default)
			)
			(layer "F.SilkS")
		)
		(fp_line
			(start 0.7874 -0.4064)
			(end 0.7874 0.4064)
			(stroke
				(width 0.1524)
				(type default)
			)
			(layer "F.SilkS")
		)
		(fp_line
			(start -0.67945 0.3048)
			(end -0.67945 -0.305054)
			(stroke
				(width 0.1)
				(type default)
			)
			(layer "F.Fab")
		)
		(fp_line
			(start -0.12065 0.3048)
			(end -0.67945 0.3048)
			(stroke
				(width 0.1)
				(type default)
			)
			(layer "F.Fab")
		)
		(fp_line
			(start 0.120396 0.3048)
			(end 0.120396 0.2794)
			(stroke
				(width 0.1)
				(type default)
			)
			(layer "F.Fab")
		)
		(fp_line
			(start 0.67945 0.3048)
			(end 0.120396 0.3048)
			(stroke
				(width 0.1)
				(type default)
			)
			(layer "F.Fab")
		)
		(fp_line
			(start -0.12065 0.2794)
			(end -0.12065 0.3048)
			(stroke
				(width 0.1)
				(type default)
			)
			(layer "F.Fab")
		)
		(fp_line
			(start 0.120396 0.2794)
			(end -0.12065 0.2794)
			(stroke
				(width 0.1)
				(type default)
			)
			(layer "F.Fab")
		)
		(fp_line
			(start -0.12065 -0.2794)
			(end 0.12065 -0.2794)
			(stroke
				(width 0.1)
				(type default)
			)
			(layer "F.Fab")
		)
		(fp_line
			(start 0.12065 -0.2794)
			(end 0.12065 -0.3048)
			(stroke
				(width 0.1)
				(type default)
			)
			(layer "F.Fab")
		)
		(fp_line
			(start 0.12065 -0.3048)
			(end 0.67945 -0.3048)
			(stroke
				(width 0.1)
				(type default)
			)
			(layer "F.Fab")
		)
		(fp_line
			(start 0.67945 -0.3048)
			(end 0.67945 0.3048)
			(stroke
				(width 0.1)
				(type default)
			)
			(layer "F.Fab")
		)
		(fp_line
			(start -0.67945 -0.305054)
			(end -0.12065 -0.305054)
			(stroke
				(width 0.1)
				(type default)
			)
			(layer "F.Fab")
		)
		(fp_line
			(start -0.12065 -0.305054)
			(end -0.12065 -0.2794)
			(stroke
				(width 0.1)
				(type default)
			)
			(layer "F.Fab")
		)
		(pad "1" smd circle
			(at -0.40005 0 270)
			(size 0 0)
			(layers "F.Cu" "F.Mask" "F.Paste")
			(net "OCP_V3_2_AUX_PWR_EN")
		)
		(pad "2" smd circle
			(at 0.40005 0 270)
			(size 0 0)
			(layers "F.Cu" "F.Mask" "F.Paste")
			(net "OCP_V3_2_AUX_PWR_EN_R")
		)
	)
	(footprint ""
		(layer "F.Cu")
		(at 82.322924 -152.621742 90)
		(property "Reference" "C537"
			(at 0 0 90)
			(layer "F.SilkS")
			(hide yes)
			(effects
				(font
					(size 1.27 1.27)
				)
			)
		)
		(property "Value" ""
			(at 0 0 90)
			(layer "F.Fab")
			(effects
				(font
					(size 1.27 1.27)
				)
			)
		)
		(duplicate_pad_numbers_are_jumpers no)
		(fp_line
			(start 0.7874 -0.4064)
			(end 0.7874 0.4064)
			(stroke
				(width 0.1524)
				(type default)
			)
			(layer "F.SilkS")
		)
		(fp_line
			(start -0.7874 -0.4064)
			(end 0.7874 -0.4064)
			(stroke
				(width 0.1524)
				(type default)
			)
			(layer "F.SilkS")
		)
		(fp_line
			(start 0.7874 0.4064)
			(end -0.7874 0.4064)
			(stroke
				(width 0.1524)
				(type default)
			)
			(layer "F.SilkS")
		)
		(fp_line
			(start -0.7874 0.4064)
			(end -0.7874 -0.4064)
			(stroke
				(width 0.1524)
				(type default)
			)
			(layer "F.SilkS")
		)
		(fp_line
			(start -0.12065 -0.305054)
			(end -0.12065 -0.2794)
			(stroke
				(width 0.1)
				(type default)
			)
			(layer "F.Fab")
		)
		(fp_line
			(start -0.67945 -0.305054)
			(end -0.12065 -0.305054)
			(stroke
				(width 0.1)
				(type default)
			)
			(layer "F.Fab")
		)
		(fp_line
			(start 0.67945 -0.3048)
			(end 0.67945 0.3048)
			(stroke
				(width 0.1)
				(type default)
			)
			(layer "F.Fab")
		)
		(fp_line
			(start 0.12065 -0.3048)
			(end 0.67945 -0.3048)
			(stroke
				(width 0.1)
				(type default)
			)
			(layer "F.Fab")
		)
		(fp_line
			(start 0.12065 -0.2794)
			(end 0.12065 -0.3048)
			(stroke
				(width 0.1)
				(type default)
			)
			(layer "F.Fab")
		)
		(fp_line
			(start -0.12065 -0.2794)
			(end 0.12065 -0.2794)
			(stroke
				(width 0.1)
				(type default)
			)
			(layer "F.Fab")
		)
		(fp_line
			(start 0.120396 0.2794)
			(end -0.12065 0.2794)
			(stroke
				(width 0.1)
				(type default)
			)
			(layer "F.Fab")
		)
		(fp_line
			(start -0.12065 0.2794)
			(end -0.12065 0.3048)
			(stroke
				(width 0.1)
				(type default)
			)
			(layer "F.Fab")
		)
		(fp_line
			(start 0.67945 0.3048)
			(end 0.120396 0.3048)
			(stroke
				(width 0.1)
				(type default)
			)
			(layer "F.Fab")
		)
		(fp_line
			(start 0.120396 0.3048)
			(end 0.120396 0.2794)
			(stroke
				(width 0.1)
				(type default)
			)
			(layer "F.Fab")
		)
		(fp_line
			(start -0.12065 0.3048)
			(end -0.67945 0.3048)
			(stroke
				(width 0.1)
				(type default)
			)
			(layer "F.Fab")
		)
		(fp_line
			(start -0.67945 0.3048)
			(end -0.67945 -0.305054)
			(stroke
				(width 0.1)
				(type default)
			)
			(layer "F.Fab")
		)
		(pad "1" smd circle
			(at -0.40005 0 90)
			(size 0 0)
			(layers "F.Cu" "F.Mask" "F.Paste")
			(net "P3V3_AUX")
		)
		(pad "2" smd circle
			(at 0.40005 0 90)
			(size 0 0)
			(layers "F.Cu" "F.Mask" "F.Paste")
			(net "GND")
		)
	)
)
